(kicad_pcb
	(version 20260206)
	(generator "pcbnew")
	(generator_version "10.0")
	(general
		(thickness 1.6)
		(legacy_teardrops no)
	)
	(paper "A4")
	(title_block
		(title "04192023_DAF0TMB3IC0_F0TG_MB_C_brd_V02_OCP.brd")
		(comment 1 "Grand Teton / footprints 1376-1383 of 8354")
	)
	(layers
		(0 "F.Cu" signal "TOP")
		(4 "In1.Cu" signal "GND")
		(6 "In2.Cu" signal "IN1")
		(8 "In3.Cu" signal "GND1")
		(10 "In4.Cu" signal "IN2")
		(12 "In5.Cu" signal "GND2")
		(14 "In6.Cu" signal "IN3")
		(16 "In7.Cu" signal "GND3")
		(18 "In8.Cu" signal "VCC")
		(20 "In9.Cu" signal "VCC1")
		(22 "In10.Cu" signal "GND4")
		(24 "In11.Cu" signal "IN4")
		(26 "In12.Cu" signal "GND5")
		(28 "In13.Cu" signal "IN5")
		(30 "In14.Cu" signal "GND6")
		(32 "In15.Cu" signal "IN6")
		(34 "In16.Cu" signal "GND7")
		(2 "B.Cu" signal "BOTTOM")
		(9 "F.Adhes" user "F.Adhesive")
		(11 "B.Adhes" user "B.Adhesive")
		(13 "F.Paste" user "Package Geometry/Pastemask Top")
		(15 "B.Paste" user "Package Geometry/Pastemask Bottom")
		(5 "F.SilkS" user "Ref Des/Silkscreen Top")
		(7 "B.SilkS" user "Ref Des/Silkscreen Bottom")
		(1 "F.Mask" user "Board Geometry/Soldermask Top")
		(3 "B.Mask" user "Board Geometry/Soldermask Bottom")
		(17 "Dwgs.User" user "User.Drawings")
		(19 "Cmts.User" user "User.Comments")
		(21 "Eco1.User" user "User.Eco1")
		(23 "Eco2.User" user "User.Eco2")
		(25 "Edge.Cuts" user "Board Geometry/Outline")
		(27 "Margin" user)
		(31 "F.CrtYd" user "Package Geometry/Place Bound Top")
		(29 "B.CrtYd" user "Package Geometry/Place Bound Bottom")
		(35 "F.Fab" user "Ref Des/Assembly Top")
		(33 "B.Fab" user "Ref Des/Assembly Bottom")
	)
	(footprint ""
		(layer "F.Cu")
		(at 66.027554 -370.57203 -90)
		(property "Reference" "C812"
			(at 0 0 270)
			(layer "F.SilkS")
			(hide yes)
			(effects
				(font
					(size 1.27 1.27)
				)
			)
		)
		(property "Value" ""
			(at 0 0 270)
			(layer "F.Fab")
			(effects
				(font
					(size 1.27 1.27)
				)
			)
		)
		(duplicate_pad_numbers_are_jumpers no)
		(fp_line
			(start -0.299974 0.150114)
			(end -0.299974 -0.150114)
			(stroke
				(width 0.1)
				(type default)
			)
			(layer "F.Fab")
		)
		(fp_line
			(start 0.299974 0.150114)
			(end -0.299974 0.150114)
			(stroke
				(width 0.1)
				(type default)
			)
			(layer "F.Fab")
		)
		(fp_line
			(start -0.299974 -0.150114)
			(end 0.299974 -0.150114)
			(stroke
				(width 0.1)
				(type default)
			)
			(layer "F.Fab")
		)
		(fp_line
			(start 0.299974 -0.150114)
			(end 0.299974 0.150114)
			(stroke
				(width 0.1)
				(type default)
			)
			(layer "F.Fab")
		)
		(pad "1" smd rect
			(at -0.2667 0 270)
			(size 0.3048 0.381)
			(layers "F.Cu" "F.Mask" "F.Paste")
			(net "P5E_CPU1_P0_TX_C_DN<12>")
		)
		(pad "2" smd rect
			(at 0.2667 0 270)
			(size 0.3048 0.381)
			(layers "F.Cu" "F.Mask" "F.Paste")
			(net "P5E_CPU1_P0_TX_DN<12>")
		)
	)
	(footprint ""
		(layer "F.Cu")
		(at 332.431644 -381.41783 -90)
		(property "Reference" "C960"
			(at 0 0 270)
			(layer "F.SilkS")
			(hide yes)
			(effects
				(font
					(size 1.27 1.27)
				)
			)
		)
		(property "Value" ""
			(at 0 0 270)
			(layer "F.Fab")
			(effects
				(font
					(size 1.27 1.27)
				)
			)
		)
		(duplicate_pad_numbers_are_jumpers no)
		(fp_line
			(start -0.299974 0.150114)
			(end -0.299974 -0.150114)
			(stroke
				(width 0.1)
				(type default)
			)
			(layer "F.Fab")
		)
		(fp_line
			(start 0.299974 0.150114)
			(end -0.299974 0.150114)
			(stroke
				(width 0.1)
				(type default)
			)
			(layer "F.Fab")
		)
		(fp_line
			(start -0.299974 -0.150114)
			(end 0.299974 -0.150114)
			(stroke
				(width 0.1)
				(type default)
			)
			(layer "F.Fab")
		)
		(fp_line
			(start 0.299974 -0.150114)
			(end 0.299974 0.150114)
			(stroke
				(width 0.1)
				(type default)
			)
			(layer "F.Fab")
		)
		(pad "1" smd rect
			(at -0.2667 0 270)
			(size 0.3048 0.381)
			(layers "F.Cu" "F.Mask" "F.Paste")
			(net "P5E_CPU0_P1_TX_C_DN<2>")
		)
		(pad "2" smd rect
			(at 0.2667 0 270)
			(size 0.3048 0.381)
			(layers "F.Cu" "F.Mask" "F.Paste")
			(net "P5E_CPU0_P1_TX_DN<2>")
		)
	)
	(footprint ""
		(layer "F.Cu")
		(at 64.63538 -394.78966 -90)
		(property "Reference" "R701"
			(at 0 0 270)
			(layer "F.SilkS")
			(hide yes)
			(effects
				(font
					(size 1.27 1.27)
				)
			)
		)
		(property "Value" ""
			(at 0 0 270)
			(layer "F.Fab")
			(effects
				(font
					(size 1.27 1.27)
				)
			)
		)
		(duplicate_pad_numbers_are_jumpers no)
		(fp_line
			(start -0.32512 0.175006)
			(end -0.32512 -0.175006)
			(stroke
				(width 0.1)
				(type default)
			)
			(layer "F.Fab")
		)
		(fp_line
			(start 0.32512 0.175006)
			(end -0.32512 0.175006)
			(stroke
				(width 0.1)
				(type default)
			)
			(layer "F.Fab")
		)
		(fp_line
			(start -0.32512 -0.175006)
			(end 0.32512 -0.175006)
			(stroke
				(width 0.1)
				(type default)
			)
			(layer "F.Fab")
		)
		(fp_line
			(start 0.32512 -0.175006)
			(end 0.32512 0.175006)
			(stroke
				(width 0.1)
				(type default)
			)
			(layer "F.Fab")
		)
		(pad "1" smd rect
			(at -0.2667 0 270)
			(size 0.3048 0.381)
			(layers "F.Cu" "F.Mask" "F.Paste")
			(net "RT_CPU1_P0_VQPS")
		)
		(pad "2" smd rect
			(at 0.2667 0 90)
			(size 0.3048 0.381)
			(layers "F.Cu" "F.Mask" "F.Paste")
			(net "GND")
		)
	)
	(footprint ""
		(layer "F.Cu")
		(at 70.720204 -144.881092 180)
		(property "Reference" "PR401"
			(at 0 0 180)
			(layer "F.SilkS")
			(hide yes)
			(effects
				(font
					(size 1.27 1.27)
				)
			)
		)
		(property "Value" ""
			(at 0 0 180)
			(layer "F.Fab")
			(effects
				(font
					(size 1.27 1.27)
				)
			)
		)
		(duplicate_pad_numbers_are_jumpers no)
		(fp_line
			(start 0.7874 0.4064)
			(end -0.7874 0.4064)
			(stroke
				(width 0.1524)
				(type default)
			)
			(layer "F.SilkS")
		)
		(fp_line
			(start 0.7874 -0.4064)
			(end 0.7874 0.4064)
			(stroke
				(width 0.1524)
				(type default)
			)
			(layer "F.SilkS")
		)
		(fp_line
			(start -0.7874 0.4064)
			(end -0.7874 -0.4064)
			(stroke
				(width 0.1524)
				(type default)
			)
			(layer "F.SilkS")
		)
		(fp_line
			(start -0.7874 -0.4064)
			(end 0.7874 -0.4064)
			(stroke
				(width 0.1524)
				(type default)
			)
			(layer "F.SilkS")
		)
		(fp_line
			(start 0.67945 0.3048)
			(end 0.120396 0.3048)
			(stroke
				(width 0.1)
				(type default)
			)
			(layer "F.Fab")
		)
		(fp_line
			(start 0.67945 -0.3048)
			(end 0.67945 0.3048)
			(stroke
				(width 0.1)
				(type default)
			)
			(layer "F.Fab")
		)
		(fp_line
			(start 0.12065 -0.2794)
			(end 0.12065 -0.3048)
			(stroke
				(width 0.1)
				(type default)
			)
			(layer "F.Fab")
		)
		(fp_line
			(start 0.12065 -0.3048)
			(end 0.67945 -0.3048)
			(stroke
				(width 0.1)
				(type default)
			)
			(layer "F.Fab")
		)
		(fp_line
			(start 0.120396 0.3048)
			(end 0.120396 0.2794)
			(stroke
				(width 0.1)
				(type default)
			)
			(layer "F.Fab")
		)
		(fp_line
			(start 0.120396 0.2794)
			(end -0.12065 0.2794)
			(stroke
				(width 0.1)
				(type default)
			)
			(layer "F.Fab")
		)
		(fp_line
			(start -0.12065 0.3048)
			(end -0.67945 0.3048)
			(stroke
				(width 0.1)
				(type default)
			)
			(layer "F.Fab")
		)
		(fp_line
			(start -0.12065 0.2794)
			(end -0.12065 0.3048)
			(stroke
				(width 0.1)
				(type default)
			)
			(layer "F.Fab")
		)
		(fp_line
			(start -0.12065 -0.2794)
			(end 0.12065 -0.2794)
			(stroke
				(width 0.1)
				(type default)
			)
			(layer "F.Fab")
		)
		(fp_line
			(start -0.12065 -0.305054)
			(end -0.12065 -0.2794)
			(stroke
				(width 0.1)
				(type default)
			)
			(layer "F.Fab")
		)
		(fp_line
			(start -0.67945 0.3048)
			(end -0.67945 -0.305054)
			(stroke
				(width 0.1)
				(type default)
			)
			(layer "F.Fab")
		)
		(fp_line
			(start -0.67945 -0.305054)
			(end -0.12065 -0.305054)
			(stroke
				(width 0.1)
				(type default)
			)
			(layer "F.Fab")
		)
		(pad "1" smd circle
			(at -0.40005 0 180)
			(size 0 0)
			(layers "F.Cu" "F.Mask" "F.Paste")
			(net "PVDD18_SS_P1_RGND")
		)
		(pad "2" smd circle
			(at 0.40005 0 180)
			(size 0 0)
			(layers "F.Cu" "F.Mask" "F.Paste")
			(net "VSENSE_PVDD18_S5_P1_DN")
		)
	)
	(footprint ""
		(layer "F.Cu")
		(at 377.417838 -182.661052 90)
		(property "Reference" "PC550_3"
			(at 0 0 90)
			(layer "F.SilkS")
			(hide yes)
			(effects
				(font
					(size 1.27 1.27)
				)
			)
		)
		(property "Value" ""
			(at 0 0 90)
			(layer "F.Fab")
			(effects
				(font
					(size 1.27 1.27)
				)
			)
		)
		(duplicate_pad_numbers_are_jumpers no)
		(fp_line
			(start 0.7874 -0.4064)
			(end 0.7874 0.4064)
			(stroke
				(width 0.1524)
				(type default)
			)
			(layer "F.SilkS")
		)
		(fp_line
			(start -0.7874 -0.4064)
			(end 0.7874 -0.4064)
			(stroke
				(width 0.1524)
				(type default)
			)
			(layer "F.SilkS")
		)
		(fp_line
			(start 0.7874 0.4064)
			(end -0.7874 0.4064)
			(stroke
				(width 0.1524)
				(type default)
			)
			(layer "F.SilkS")
		)
		(fp_line
			(start -0.7874 0.4064)
			(end -0.7874 -0.4064)
			(stroke
				(width 0.1524)
				(type default)
			)
			(layer "F.SilkS")
		)
		(fp_line
			(start -0.12065 -0.305054)
			(end -0.12065 -0.2794)
			(stroke
				(width 0.1)
				(type default)
			)
			(layer "F.Fab")
		)
		(fp_line
			(start -0.67945 -0.305054)
			(end -0.12065 -0.305054)
			(stroke
				(width 0.1)
				(type default)
			)
			(layer "F.Fab")
		)
		(fp_line
			(start 0.67945 -0.3048)
			(end 0.67945 0.3048)
			(stroke
				(width 0.1)
				(type default)
			)
			(layer "F.Fab")
		)
		(fp_line
			(start 0.12065 -0.3048)
			(end 0.67945 -0.3048)
			(stroke
				(width 0.1)
				(type default)
			)
			(layer "F.Fab")
		)
		(fp_line
			(start 0.12065 -0.2794)
			(end 0.12065 -0.3048)
			(stroke
				(width 0.1)
				(type default)
			)
			(layer "F.Fab")
		)
		(fp_line
			(start -0.12065 -0.2794)
			(end 0.12065 -0.2794)
			(stroke
				(width 0.1)
				(type default)
			)
			(layer "F.Fab")
		)
		(fp_line
			(start 0.120396 0.2794)
			(end -0.12065 0.2794)
			(stroke
				(width 0.1)
				(type default)
			)
			(layer "F.Fab")
		)
		(fp_line
			(start -0.12065 0.2794)
			(end -0.12065 0.3048)
			(stroke
				(width 0.1)
				(type default)
			)
			(layer "F.Fab")
		)
		(fp_line
			(start 0.67945 0.3048)
			(end 0.120396 0.3048)
			(stroke
				(width 0.1)
				(type default)
			)
			(layer "F.Fab")
		)
		(fp_line
			(start 0.120396 0.3048)
			(end 0.120396 0.2794)
			(stroke
				(width 0.1)
				(type default)
			)
			(layer "F.Fab")
		)
		(fp_line
			(start -0.12065 0.3048)
			(end -0.67945 0.3048)
			(stroke
				(width 0.1)
				(type default)
			)
			(layer "F.Fab")
		)
		(fp_line
			(start -0.67945 0.3048)
			(end -0.67945 -0.305054)
			(stroke
				(width 0.1)
				(type default)
			)
			(layer "F.Fab")
		)
		(pad "1" smd circle
			(at -0.40005 0 90)
			(size 0 0)
			(layers "F.Cu" "F.Mask" "F.Paste")
			(net "SW_P12V_AUX_PVDDCR_CPU0_P0_FLT")
		)
		(pad "2" smd circle
			(at 0.40005 0 90)
			(size 0 0)
			(layers "F.Cu" "F.Mask" "F.Paste")
			(net "GND")
		)
	)
	(footprint ""
		(layer "F.Cu")
		(at 351.410778 -161.141156 90)
		(property "Reference" "PC152_C0P0_6"
			(at 0 0 90)
			(layer "F.SilkS")
			(hide yes)
			(effects
				(font
					(size 1.27 1.27)
				)
			)
		)
		(property "Value" ""
			(at 0 0 90)
			(layer "F.Fab")
			(effects
				(font
					(size 1.27 1.27)
				)
			)
		)
		(duplicate_pad_numbers_are_jumpers no)
		(fp_line
			(start 0.7874 -0.4064)
			(end 0.7874 0.4064)
			(stroke
				(width 0.1524)
				(type default)
			)
			(layer "F.SilkS")
		)
		(fp_line
			(start -0.7874 -0.4064)
			(end 0.7874 -0.4064)
			(stroke
				(width 0.1524)
				(type default)
			)
			(layer "F.SilkS")
		)
		(fp_line
			(start 0.7874 0.4064)
			(end -0.7874 0.4064)
			(stroke
				(width 0.1524)
				(type default)
			)
			(layer "F.SilkS")
		)
		(fp_line
			(start -0.7874 0.4064)
			(end -0.7874 -0.4064)
			(stroke
				(width 0.1524)
				(type default)
			)
			(layer "F.SilkS")
		)
		(fp_line
			(start -0.12065 -0.305054)
			(end -0.12065 -0.2794)
			(stroke
				(width 0.1)
				(type default)
			)
			(layer "F.Fab")
		)
		(fp_line
			(start -0.67945 -0.305054)
			(end -0.12065 -0.305054)
			(stroke
				(width 0.1)
				(type default)
			)
			(layer "F.Fab")
		)
		(fp_line
			(start 0.67945 -0.3048)
			(end 0.67945 0.3048)
			(stroke
				(width 0.1)
				(type default)
			)
			(layer "F.Fab")
		)
		(fp_line
			(start 0.12065 -0.3048)
			(end 0.67945 -0.3048)
			(stroke
				(width 0.1)
				(type default)
			)
			(layer "F.Fab")
		)
		(fp_line
			(start 0.12065 -0.2794)
			(end 0.12065 -0.3048)
			(stroke
				(width 0.1)
				(type default)
			)
			(layer "F.Fab")
		)
		(fp_line
			(start -0.12065 -0.2794)
			(end 0.12065 -0.2794)
			(stroke
				(width 0.1)
				(type default)
			)
			(layer "F.Fab")
		)
		(fp_line
			(start 0.120396 0.2794)
			(end -0.12065 0.2794)
			(stroke
				(width 0.1)
				(type default)
			)
			(layer "F.Fab")
		)
		(fp_line
			(start -0.12065 0.2794)
			(end -0.12065 0.3048)
			(stroke
				(width 0.1)
				(type default)
			)
			(layer "F.Fab")
		)
		(fp_line
			(start 0.67945 0.3048)
			(end 0.120396 0.3048)
			(stroke
				(width 0.1)
				(type default)
			)
			(layer "F.Fab")
		)
		(fp_line
			(start 0.120396 0.3048)
			(end 0.120396 0.2794)
			(stroke
				(width 0.1)
				(type default)
			)
			(layer "F.Fab")
		)
		(fp_line
			(start -0.12065 0.3048)
			(end -0.67945 0.3048)
			(stroke
				(width 0.1)
				(type default)
			)
			(layer "F.Fab")
		)
		(fp_line
			(start -0.67945 0.3048)
			(end -0.67945 -0.305054)
			(stroke
				(width 0.1)
				(type default)
			)
			(layer "F.Fab")
		)
		(pad "1" smd circle
			(at -0.40005 0 90)
			(size 0 0)
			(layers "F.Cu" "F.Mask" "F.Paste")
			(net "PVDDCR_CPU0_P0_PVCC")
		)
		(pad "2" smd circle
			(at 0.40005 0 90)
			(size 0 0)
			(layers "F.Cu" "F.Mask" "F.Paste")
			(net "GND")
		)
	)
	(footprint ""
		(layer "F.Cu")
		(at 157.018228 -23.284942 -90)
		(property "Reference" "R6010"
			(at 0 0 270)
			(layer "F.SilkS")
			(hide yes)
			(effects
				(font
					(size 1.27 1.27)
				)
			)
		)
		(property "Value" ""
			(at 0 0 270)
			(layer "F.Fab")
			(effects
				(font
					(size 1.27 1.27)
				)
			)
		)
		(duplicate_pad_numbers_are_jumpers no)
		(fp_line
			(start -0.7874 0.4064)
			(end -0.7874 -0.4064)
			(stroke
				(width 0.1524)
				(type default)
			)
			(layer "F.SilkS")
		)
		(fp_line
			(start 0.7874 0.4064)
			(end -0.7874 0.4064)
			(stroke
				(width 0.1524)
				(type default)
			)
			(layer "F.SilkS")
		)
		(fp_line
			(start -0.7874 -0.4064)
			(end 0.7874 -0.4064)
			(stroke
				(width 0.1524)
				(type default)
			)
			(layer "F.SilkS")
		)
		(fp_line
			(start 0.7874 -0.4064)
			(end 0.7874 0.4064)
			(stroke
				(width 0.1524)
				(type default)
			)
			(layer "F.SilkS")
		)
		(fp_line
			(start -0.67945 0.3048)
			(end -0.67945 -0.305054)
			(stroke
				(width 0.1)
				(type default)
			)
			(layer "F.Fab")
		)
		(fp_line
			(start -0.12065 0.3048)
			(end -0.67945 0.3048)
			(stroke
				(width 0.1)
				(type default)
			)
			(layer "F.Fab")
		)
		(fp_line
			(start 0.120396 0.3048)
			(end 0.120396 0.2794)
			(stroke
				(width 0.1)
				(type default)
			)
			(layer "F.Fab")
		)
		(fp_line
			(start 0.67945 0.3048)
			(end 0.120396 0.3048)
			(stroke
				(width 0.1)
				(type default)
			)
			(layer "F.Fab")
		)
		(fp_line
			(start -0.12065 0.2794)
			(end -0.12065 0.3048)
			(stroke
				(width 0.1)
				(type default)
			)
			(layer "F.Fab")
		)
		(fp_line
			(start 0.120396 0.2794)
			(end -0.12065 0.2794)
			(stroke
				(width 0.1)
				(type default)
			)
			(layer "F.Fab")
		)
		(fp_line
			(start -0.12065 -0.2794)
			(end 0.12065 -0.2794)
			(stroke
				(width 0.1)
				(type default)
			)
			(layer "F.Fab")
		)
		(fp_line
			(start 0.12065 -0.2794)
			(end 0.12065 -0.3048)
			(stroke
				(width 0.1)
				(type default)
			)
			(layer "F.Fab")
		)
		(fp_line
			(start 0.12065 -0.3048)
			(end 0.67945 -0.3048)
			(stroke
				(width 0.1)
				(type default)
			)
			(layer "F.Fab")
		)
		(fp_line
			(start 0.67945 -0.3048)
			(end 0.67945 0.3048)
			(stroke
				(width 0.1)
				(type default)
			)
			(layer "F.Fab")
		)
		(fp_line
			(start -0.67945 -0.305054)
			(end -0.12065 -0.305054)
			(stroke
				(width 0.1)
				(type default)
			)
			(layer "F.Fab")
		)
		(fp_line
			(start -0.12065 -0.305054)
			(end -0.12065 -0.2794)
			(stroke
				(width 0.1)
				(type default)
			)
			(layer "F.Fab")
		)
		(pad "1" smd circle
			(at -0.40005 0 270)
			(size 0 0)
			(layers "F.Cu" "F.Mask" "F.Paste")
			(net "SGPIO_SCM_DI_<0>")
		)
		(pad "2" smd circle
			(at 0.40005 0 270)
			(size 0 0)
			(layers "F.Cu" "F.Mask" "F.Paste")
			(net "SGPIO_SCM_DI_R_<0>")
		)
	)
	(footprint ""
		(layer "F.Cu")
		(at 157.81274 -44.985686 -90)
		(property "Reference" "R1700"
			(at 0 0 270)
			(layer "F.SilkS")
			(hide yes)
			(effects
				(font
					(size 1.27 1.27)
				)
			)
		)
		(property "Value" ""
			(at 0 0 270)
			(layer "F.Fab")
			(effects
				(font
					(size 1.27 1.27)
				)
			)
		)
		(duplicate_pad_numbers_are_jumpers no)
		(fp_line
			(start -0.7874 0.4064)
			(end -0.7874 -0.4064)
			(stroke
				(width 0.1524)
				(type default)
			)
			(layer "F.SilkS")
		)
		(fp_line
			(start 0.7874 0.4064)
			(end -0.7874 0.4064)
			(stroke
				(width 0.1524)
				(type default)
			)
			(layer "F.SilkS")
		)
		(fp_line
			(start -0.7874 -0.4064)
			(end 0.7874 -0.4064)
			(stroke
				(width 0.1524)
				(type default)
			)
			(layer "F.SilkS")
		)
		(fp_line
			(start 0.7874 -0.4064)
			(end 0.7874 0.4064)
			(stroke
				(width 0.1524)
				(type default)
			)
			(layer "F.SilkS")
		)
		(fp_line
			(start -0.67945 0.3048)
			(end -0.67945 -0.305054)
			(stroke
				(width 0.1)
				(type default)
			)
			(layer "F.Fab")
		)
		(fp_line
			(start -0.12065 0.3048)
			(end -0.67945 0.3048)
			(stroke
				(width 0.1)
				(type default)
			)
			(layer "F.Fab")
		)
		(fp_line
			(start 0.120396 0.3048)
			(end 0.120396 0.2794)
			(stroke
				(width 0.1)
				(type default)
			)
			(layer "F.Fab")
		)
		(fp_line
			(start 0.67945 0.3048)
			(end 0.120396 0.3048)
			(stroke
				(width 0.1)
				(type default)
			)
			(layer "F.Fab")
		)
		(fp_line
			(start -0.12065 0.2794)
			(end -0.12065 0.3048)
			(stroke
				(width 0.1)
				(type default)
			)
			(layer "F.Fab")
		)
		(fp_line
			(start 0.120396 0.2794)
			(end -0.12065 0.2794)
			(stroke
				(width 0.1)
				(type default)
			)
			(layer "F.Fab")
		)
		(fp_line
			(start -0.12065 -0.2794)
			(end 0.12065 -0.2794)
			(stroke
				(width 0.1)
				(type default)
			)
			(layer "F.Fab")
		)
		(fp_line
			(start 0.12065 -0.2794)
			(end 0.12065 -0.3048)
			(stroke
				(width 0.1)
				(type default)
			)
			(layer "F.Fab")
		)
		(fp_line
			(start 0.12065 -0.3048)
			(end 0.67945 -0.3048)
			(stroke
				(width 0.1)
				(type default)
			)
			(layer "F.Fab")
		)
		(fp_line
			(start 0.67945 -0.3048)
			(end 0.67945 0.3048)
			(stroke
				(width 0.1)
				(type default)
			)
			(layer "F.Fab")
		)
		(fp_line
			(start -0.67945 -0.305054)
			(end -0.12065 -0.305054)
			(stroke
				(width 0.1)
				(type default)
			)
			(layer "F.Fab")
		)
		(fp_line
			(start -0.12065 -0.305054)
			(end -0.12065 -0.2794)
			(stroke
				(width 0.1)
				(type default)
			)
			(layer "F.Fab")
		)
		(pad "1" smd circle
			(at -0.40005 0 270)
			(size 0 0)
			(layers "F.Cu" "F.Mask" "F.Paste")
			(net "P3V3_AUX")
		)
		(pad "2" smd circle
			(at 0.40005 0 270)
			(size 0 0)
			(layers "F.Cu" "F.Mask" "F.Paste")
			(net "SMB_PCIE_M2_0_EN")
		)
	)
)
